(kicad_pcb
	(version 20241229)
	(generator "pcbnew")
	(generator_version "9.0")
	(general
		(thickness 1.294)
		(legacy_teardrops no)
	)
	(paper "A3")
	(title_block
		(title "Kintex 410T devboard")
		(date "2024-04-03")
		(rev "1.1.2")
		(comment 9 "footprints 898-903 of 975")
	)
	(layers
		(0 "F.Cu" mixed)
		(4 "In1.Cu" power)
		(6 "In2.Cu" power)
		(8 "In3.Cu" mixed)
		(10 "In4.Cu" power)
		(12 "In5.Cu" mixed)
		(14 "In6.Cu" power)
		(16 "In7.Cu" mixed)
		(18 "In8.Cu" power)
		(2 "B.Cu" mixed)
		(9 "F.Adhes" user "F.Adhesive")
		(11 "B.Adhes" user "B.Adhesive")
		(13 "F.Paste" user)
		(15 "B.Paste" user)
		(5 "F.SilkS" user "F.Silkscreen")
		(7 "B.SilkS" user "B.Silkscreen")
		(1 "F.Mask" user)
		(3 "B.Mask" user)
		(17 "Dwgs.User" user "User.Drawings")
		(19 "Cmts.User" user "User.Comments")
		(21 "Eco1.User" user "User.Eco1")
		(23 "Eco2.User" user "User.Eco2")
		(25 "Edge.Cuts" user)
		(27 "Margin" user)
		(31 "F.CrtYd" user "F.Courtyard")
		(29 "B.CrtYd" user "B.Courtyard")
		(35 "F.Fab" user)
		(33 "B.Fab" user)
	)
	(footprint "antmicro-footprints:R_0402_1005Metric"
		(layer "B.Cu")
		(at 220.6 124.8)
		(descr "Resistor SMD 0402")
		(tags "resistor SMD 0402")
		(property "Reference" "R19"
			(at 1.325 -2.5 180)
			(layer "B.SilkS")
			(effects
				(font
					(size 0.7 0.7)
					(thickness 0.15)
				)
				(justify left bottom mirror)
			)
		)
		(property "Value" "R_0R_0402"
			(at 0 -1.4 180)
			(layer "B.Fab")
			(effects
				(font
					(size 0.7 0.7)
					(thickness 0.15)
				)
				(justify left bottom mirror)
			)
		)
		(property "Description" "SMD Chip Resistor, Jumper, 0 ohm, 100 mW, 0402 [1005 Metric], Thick Film, General Purpose"
			(at 0 0 0)
			(layer "F.Fab")
			(hide yes)
			(effects
				(font
					(size 1.27 1.27)
					(thickness 0.15)
				)
			)
		)
		(property "Author" "Antmicro"
			(at 0 0 0)
			(layer "B.Fab")
			(hide yes)
			(effects
				(font
					(size 1 1)
					(thickness 0.15)
				)
				(justify mirror)
			)
		)
		(property "Current" "1A"
			(at 0 0 0)
			(layer "B.Fab")
			(hide yes)
			(effects
				(font
					(size 1 1)
					(thickness 0.15)
				)
				(justify mirror)
			)
		)
		(property "License" "Apache-2.0"
			(at 0 0 0)
			(layer "B.Fab")
			(hide yes)
			(effects
				(font
					(size 1 1)
					(thickness 0.15)
				)
				(justify mirror)
			)
		)
		(property "MPN" "ERJ2GE0R00X"
			(at 0 0 0)
			(layer "B.Fab")
			(hide yes)
			(effects
				(font
					(size 1 1)
					(thickness 0.15)
				)
				(justify mirror)
			)
		)
		(property "Manufacturer" "Panasonic"
			(at 0 0 0)
			(layer "B.Fab")
			(hide yes)
			(effects
				(font
					(size 1 1)
					(thickness 0.15)
				)
				(justify mirror)
			)
		)
		(property "Tolerance" ""
			(at 0 0 0)
			(layer "B.Fab")
			(hide yes)
			(effects
				(font
					(size 1 1)
					(thickness 0.15)
				)
				(justify mirror)
			)
		)
		(property "Val" "0R"
			(at 0 0 0)
			(layer "B.Fab")
			(hide yes)
			(effects
				(font
					(size 1 1)
					(thickness 0.15)
				)
				(justify mirror)
			)
		)
		(sheetname "User GPIO + LED + button + DIP switch")
		(sheetfile "user-gpio.kicad_sch")
		(attr smd)
		(fp_rect
			(start -0.925 0.47)
			(end 0.925 -0.47)
			(stroke
				(width 0.05)
				(type default)
			)
			(fill no)
			(layer "B.CrtYd")
		)
		(fp_rect
			(start -0.5 0.25)
			(end 0.5 -0.25)
			(stroke
				(width 0.15)
				(type solid)
			)
			(fill no)
			(layer "B.Fab")
		)
		(pad "1" smd roundrect
			(at -0.48 0)
			(size 0.59 0.64)
			(layers "B.Cu" "B.Mask" "B.Paste")
			(roundrect_rratio 0.25)
			(net 1350 "/SUP_MCU.FAN_PWM")
			(pintype "passive")
		)
		(pad "2" smd roundrect
			(at 0.48 0)
			(size 0.59 0.64)
			(layers "B.Cu" "B.Mask" "B.Paste")
			(roundrect_rratio 0.25)
			(net 876 "/User GPIO + LED + button + DIP switch/FAN_PWM_CTRL_AON")
			(pintype "passive")
		)
	)
	(footprint "antmicro-footprints:C_0805_2012Metric"
		(layer "B.Cu")
		(at 224.725 161.05 -90)
		(descr "Capacitor SMD 0805")
		(tags "capacitor SMD 0805")
		(property "Reference" "C198"
			(at -1.5 1.15 90)
			(layer "B.SilkS")
			(effects
				(font
					(size 0.7 0.7)
					(thickness 0.15)
				)
				(justify left bottom mirror)
			)
		)
		(property "Value" "C_100n_100V_0805"
			(at 0 -1.947 90)
			(layer "B.Fab")
			(effects
				(font
					(size 0.7 0.7)
					(thickness 0.15)
				)
				(justify left bottom mirror)
			)
		)
		(property "Description" "SMT Multilayer Ceramic Capacitor, 0.1 µF, 100 V, 0805 [2012 Metric], ± 10%, X7R, CL"
			(at 0 0 270)
			(layer "F.Fab")
			(hide yes)
			(effects
				(font
					(size 1.27 1.27)
					(thickness 0.15)
				)
			)
		)
		(property "Author" "Antmicro"
			(at 63.675 385.775 0)
			(layer "B.Fab")
			(hide yes)
			(effects
				(font
					(size 1 1)
					(thickness 0.15)
				)
				(justify mirror)
			)
		)
		(property "Dielectric" "X7R"
			(at 63.675 385.775 0)
			(layer "B.Fab")
			(hide yes)
			(effects
				(font
					(size 1 1)
					(thickness 0.15)
				)
				(justify mirror)
			)
		)
		(property "License" "Apache-2.0"
			(at 63.675 385.775 0)
			(layer "B.Fab")
			(hide yes)
			(effects
				(font
					(size 1 1)
					(thickness 0.15)
				)
				(justify mirror)
			)
		)
		(property "MPN" "CL21B104KCFNNNE"
			(at 63.675 385.775 0)
			(layer "B.Fab")
			(hide yes)
			(effects
				(font
					(size 1 1)
					(thickness 0.15)
				)
				(justify mirror)
			)
		)
		(property "Manufacturer" "Samsung Electro-Mechanics"
			(at 63.675 385.775 0)
			(layer "B.Fab")
			(hide yes)
			(effects
				(font
					(size 1 1)
					(thickness 0.15)
				)
				(justify mirror)
			)
		)
		(property "Val" "100n"
			(at 63.675 385.775 0)
			(layer "B.Fab")
			(hide yes)
			(effects
				(font
					(size 1 1)
					(thickness 0.15)
				)
				(justify mirror)
			)
		)
		(property "Voltage" "100V"
			(at 63.675 385.775 0)
			(layer "B.Fab")
			(hide yes)
			(effects
				(font
					(size 1 1)
					(thickness 0.15)
				)
				(justify mirror)
			)
		)
		(sheetname "Power supply")
		(sheetfile "power-supply.kicad_sch")
		(attr smd)
		(fp_line
			(start -0.3 0.7)
			(end 0.3 0.7)
			(stroke
				(width 0.15)
				(type solid)
			)
			(layer "B.SilkS")
		)
		(fp_line
			(start -0.3 -0.7)
			(end 0.3 -0.7)
			(stroke
				(width 0.15)
				(type solid)
			)
			(layer "B.SilkS")
		)
		(fp_rect
			(start 1.95 0.9)
			(end -1.95 -0.9)
			(stroke
				(width 0.05)
				(type default)
			)
			(fill no)
			(layer "B.CrtYd")
		)
		(fp_rect
			(start -0.95 0.675)
			(end 0.95 -0.675)
			(stroke
				(width 0.15)
				(type solid)
			)
			(fill no)
			(layer "B.Fab")
		)
		(pad "1" smd roundrect
			(at -1.1 0 270)
			(size 1.2 1.3)
			(layers "B.Cu" "B.Mask" "B.Paste")
			(roundrect_rratio 0.25)
			(net 700 "/Power supply/USB_PD_VBUS")
			(pintype "passive")
		)
		(pad "2" smd roundrect
			(at 1.1 0 270)
			(size 1.2 1.3)
			(layers "B.Cu" "B.Mask" "B.Paste")
			(roundrect_rratio 0.25)
			(net 1227 "Net-(C198-Pad2)")
			(pintype "passive")
		)
	)
	(footprint "antmicro-footprints:C_0402_1005Metric"
		(layer "B.Cu")
		(at 251.501 161.6 -90)
		(descr "Capacitor SMD 0402")
		(tags "capacitor SMD 0402")
		(property "Reference" "C283"
			(at -1.375 -5.999 90)
			(layer "B.SilkS")
			(effects
				(font
					(size 0.7 0.7)
					(thickness 0.15)
				)
				(justify left bottom mirror)
			)
		)
		(property "Value" "C_100n_0402"
			(at 0 -1.169 90)
			(layer "B.Fab")
			(effects
				(font
					(size 0.7 0.7)
					(thickness 0.15)
				)
				(justify left bottom mirror)
			)
		)
		(property "Description" "SMD Multilayer Ceramic Capacitor, 0.1 µF, 50 V, 0402 [1005 Metric], ± 10%, X5R, GRM Series"
			(at 0 0 270)
			(layer "F.Fab")
			(hide yes)
			(effects
				(font
					(size 1.27 1.27)
					(thickness 0.15)
				)
			)
		)
		(property "Author" "Antmicro"
			(at 89.901 413.101 0)
			(layer "B.Fab")
			(hide yes)
			(effects
				(font
					(size 1 1)
					(thickness 0.15)
				)
				(justify mirror)
			)
		)
		(property "Dielectric" "X5R"
			(at 89.901 413.101 0)
			(layer "B.Fab")
			(hide yes)
			(effects
				(font
					(size 1 1)
					(thickness 0.15)
				)
				(justify mirror)
			)
		)
		(property "License" "Apache-2.0"
			(at 89.901 413.101 0)
			(layer "B.Fab")
			(hide yes)
			(effects
				(font
					(size 1 1)
					(thickness 0.15)
				)
				(justify mirror)
			)
		)
		(property "MPN" "GRM155R61H104KE14D"
			(at 89.901 413.101 0)
			(layer "B.Fab")
			(hide yes)
			(effects
				(font
					(size 1 1)
					(thickness 0.15)
				)
				(justify mirror)
			)
		)
		(property "Manufacturer" "Murata"
			(at 89.901 413.101 0)
			(layer "B.Fab")
			(hide yes)
			(effects
				(font
					(size 1 1)
					(thickness 0.15)
				)
				(justify mirror)
			)
		)
		(property "Val" "100n"
			(at 89.901 413.101 0)
			(layer "B.Fab")
			(hide yes)
			(effects
				(font
					(size 1 1)
					(thickness 0.15)
				)
				(justify mirror)
			)
		)
		(property "Voltage" "50V"
			(at 89.901 413.101 0)
			(layer "B.Fab")
			(hide yes)
			(effects
				(font
					(size 1 1)
					(thickness 0.15)
				)
				(justify mirror)
			)
		)
		(sheetname "HDMI + Ethernet")
		(sheetfile "hdmi-ethernet.kicad_sch")
		(attr smd)
		(fp_rect
			(start -0.925 0.47)
			(end 0.925 -0.47)
			(stroke
				(width 0.05)
				(type default)
			)
			(fill no)
			(layer "B.CrtYd")
		)
		(fp_line
			(start -0.494 0.25)
			(end 0.504 0.25)
			(stroke
				(width 0.15)
				(type solid)
			)
			(layer "B.Fab")
		)
		(fp_line
			(start 0.504 0.25)
			(end 0.504 -0.248)
			(stroke
				(width 0.15)
				(type solid)
			)
			(layer "B.Fab")
		)
		(fp_line
			(start -0.494 -0.248)
			(end -0.494 0.25)
			(stroke
				(width 0.15)
				(type solid)
			)
			(layer "B.Fab")
		)
		(fp_line
			(start 0.504 -0.248)
			(end -0.494 -0.248)
			(stroke
				(width 0.15)
				(type solid)
			)
			(layer "B.Fab")
		)
		(pad "1" smd roundrect
			(at -0.48 0 270)
			(size 0.59 0.64)
			(layers "B.Cu" "B.Mask" "B.Paste")
			(roundrect_rratio 0.25)
			(net 1 "GND")
			(pintype "passive")
		)
		(pad "2" smd roundrect
			(at 0.48 0 270)
			(size 0.59 0.64)
			(layers "B.Cu" "B.Mask" "B.Paste")
			(roundrect_rratio 0.25)
			(net 721 "/HDMI + Ethernet/ETH_3V3")
			(pintype "passive")
		)
	)
	(footprint "antmicro-footprints:C_0402_1005Metric"
		(layer "B.Cu")
		(at 194.475 133.2)
		(descr "Capacitor SMD 0402")
		(tags "capacitor SMD 0402")
		(property "Reference" "C55"
			(at 24.175 -28.075 180)
			(layer "B.SilkS")
			(effects
				(font
					(size 0.7 0.7)
					(thickness 0.15)
				)
				(justify left bottom mirror)
			)
		)
		(property "Value" "C_100n_0402"
			(at 0 -1.169 180)
			(layer "B.Fab")
			(effects
				(font
					(size 0.7 0.7)
					(thickness 0.15)
				)
				(justify left bottom mirror)
			)
		)
		(property "Description" "SMD Multilayer Ceramic Capacitor, 0.1 µF, 50 V, 0402 [1005 Metric], ± 10%, X5R, GRM Series"
			(at 0 0 0)
			(layer "F.Fab")
			(hide yes)
			(effects
				(font
					(size 1.27 1.27)
					(thickness 0.15)
				)
			)
		)
		(property "Author" "Antmicro"
			(at 0 0 0)
			(layer "B.Fab")
			(hide yes)
			(effects
				(font
					(size 1 1)
					(thickness 0.15)
				)
				(justify mirror)
			)
		)
		(property "Dielectric" "X5R"
			(at 0 0 0)
			(layer "B.Fab")
			(hide yes)
			(effects
				(font
					(size 1 1)
					(thickness 0.15)
				)
				(justify mirror)
			)
		)
		(property "License" "Apache-2.0"
			(at 0 0 0)
			(layer "B.Fab")
			(hide yes)
			(effects
				(font
					(size 1 1)
					(thickness 0.15)
				)
				(justify mirror)
			)
		)
		(property "MPN" "GRM155R61H104KE14D"
			(at 0 0 0)
			(layer "B.Fab")
			(hide yes)
			(effects
				(font
					(size 1 1)
					(thickness 0.15)
				)
				(justify mirror)
			)
		)
		(property "Manufacturer" "Murata"
			(at 0 0 0)
			(layer "B.Fab")
			(hide yes)
			(effects
				(font
					(size 1 1)
					(thickness 0.15)
				)
				(justify mirror)
			)
		)
		(property "Val" "100n"
			(at 0 0 0)
			(layer "B.Fab")
			(hide yes)
			(effects
				(font
					(size 1 1)
					(thickness 0.15)
				)
				(justify mirror)
			)
		)
		(property "Voltage" "50V"
			(at 0 0 0)
			(layer "B.Fab")
			(hide yes)
			(effects
				(font
					(size 1 1)
					(thickness 0.15)
				)
				(justify mirror)
			)
		)
		(sheetname "FPGA supply")
		(sheetfile "fpga-supply.kicad_sch")
		(attr smd)
		(fp_rect
			(start -0.925 0.47)
			(end 0.925 -0.47)
			(stroke
				(width 0.05)
				(type default)
			)
			(fill no)
			(layer "B.CrtYd")
		)
		(fp_line
			(start -0.494 -0.248)
			(end -0.494 0.25)
			(stroke
				(width 0.15)
				(type solid)
			)
			(layer "B.Fab")
		)
		(fp_line
			(start -0.494 0.25)
			(end 0.504 0.25)
			(stroke
				(width 0.15)
				(type solid)
			)
			(layer "B.Fab")
		)
		(fp_line
			(start 0.504 -0.248)
			(end -0.494 -0.248)
			(stroke
				(width 0.15)
				(type solid)
			)
			(layer "B.Fab")
		)
		(fp_line
			(start 0.504 0.25)
			(end 0.504 -0.248)
			(stroke
				(width 0.15)
				(type solid)
			)
			(layer "B.Fab")
		)
		(pad "1" smd roundrect
			(at -0.48 0)
			(size 0.59 0.64)
			(layers "B.Cu" "B.Mask" "B.Paste")
			(roundrect_rratio 0.25)
			(net 1 "GND")
			(pintype "passive")
		)
		(pad "2" smd roundrect
			(at 0.48 0)
			(size 0.59 0.64)
			(layers "B.Cu" "B.Mask" "B.Paste")
			(roundrect_rratio 0.25)
			(net 26 "+1V8")
			(pintype "passive")
		)
	)
	(footprint "antmicro-footprints:R_0402_1005Metric"
		(layer "B.Cu")
		(at 159.515001 83.635001)
		(descr "Resistor SMD 0402")
		(tags "resistor SMD 0402")
		(property "Reference" "R276"
			(at -0.765001 0.389999 180)
			(layer "B.SilkS")
			(effects
				(font
					(size 0.7 0.7)
					(thickness 0.15)
				)
				(justify left bottom mirror)
			)
		)
		(property "Value" "R_33R_0402"
			(at 0 -1.4 180)
			(layer "B.Fab")
			(effects
				(font
					(size 0.7 0.7)
					(thickness 0.15)
				)
				(justify left bottom mirror)
			)
		)
		(property "Description" "SMD Chip Resistor, 33 ohm, ± 1%, 62.5 mW, 0402 [1005 Metric], Thick Film, General Purpose"
			(at 0 0 0)
			(layer "F.Fab")
			(hide yes)
			(effects
				(font
					(size 1.27 1.27)
					(thickness 0.15)
				)
			)
		)
		(property "Author" "Antmicro"
			(at 0 0 0)
			(layer "B.Fab")
			(hide yes)
			(effects
				(font
					(size 1 1)
					(thickness 0.15)
				)
				(justify mirror)
			)
		)
		(property "License" "Apache-2.0"
			(at 0 0 0)
			(layer "B.Fab")
			(hide yes)
			(effects
				(font
					(size 1 1)
					(thickness 0.15)
				)
				(justify mirror)
			)
		)
		(property "MPN" "CR0402-FX-33R0GLF"
			(at 0 0 0)
			(layer "B.Fab")
			(hide yes)
			(effects
				(font
					(size 1 1)
					(thickness 0.15)
				)
				(justify mirror)
			)
		)
		(property "Manufacturer" "Bourns"
			(at 0 0 0)
			(layer "B.Fab")
			(hide yes)
			(effects
				(font
					(size 1 1)
					(thickness 0.15)
				)
				(justify mirror)
			)
		)
		(property "Tolerance" "1%"
			(at 0 0 0)
			(layer "B.Fab")
			(hide yes)
			(effects
				(font
					(size 1 1)
					(thickness 0.15)
				)
				(justify mirror)
			)
		)
		(property "Val" "33R"
			(at 0 0 0)
			(layer "B.Fab")
			(hide yes)
			(effects
				(font
					(size 1 1)
					(thickness 0.15)
				)
				(justify mirror)
			)
		)
		(sheetname "FMC+ HSPC")
		(sheetfile "fmc-hspc.kicad_sch")
		(attr smd)
		(fp_rect
			(start -0.925 0.47)
			(end 0.925 -0.47)
			(stroke
				(width 0.05)
				(type default)
			)
			(fill no)
			(layer "B.CrtYd")
		)
		(fp_rect
			(start -0.5 0.25)
			(end 0.5 -0.25)
			(stroke
				(width 0.15)
				(type solid)
			)
			(fill no)
			(layer "B.Fab")
		)
		(pad "1" smd roundrect
			(at -0.48 0)
			(size 0.59 0.64)
			(layers "B.Cu" "B.Mask" "B.Paste")
			(roundrect_rratio 0.25)
			(net 599 "/FMC+ HSPC/GTR_REFCLK3_R_N")
			(pintype "passive")
		)
		(pad "2" smd roundrect
			(at 0.48 0)
			(size 0.59 0.64)
			(layers "B.Cu" "B.Mask" "B.Paste")
			(roundrect_rratio 0.25)
			(net 600 "/FMC+ HSPC/GTX116.REFCLK1_N")
			(pintype "passive")
		)
	)
	(footprint "antmicro-footprints:R_0402_1005Metric"
		(layer "B.Cu")
		(at 158.245001 86.195001)
		(descr "Resistor SMD 0402")
		(tags "resistor SMD 0402")
		(property "Reference" "R274"
			(at -0.795001 0.279999 180)
			(layer "B.SilkS")
			(effects
				(font
					(size 0.7 0.7)
					(thickness 0.15)
				)
				(justify left bottom mirror)
			)
		)
		(property "Value" "R_33R_0402"
			(at 0 -1.4 180)
			(layer "B.Fab")
			(effects
				(font
					(size 0.7 0.7)
					(thickness 0.15)
				)
				(justify left bottom mirror)
			)
		)
		(property "Description" "SMD Chip Resistor, 33 ohm, ± 1%, 62.5 mW, 0402 [1005 Metric], Thick Film, General Purpose"
			(at 0 0 0)
			(layer "F.Fab")
			(hide yes)
			(effects
				(font
					(size 1.27 1.27)
					(thickness 0.15)
				)
			)
		)
		(property "Author" "Antmicro"
			(at 0 0 0)
			(layer "B.Fab")
			(hide yes)
			(effects
				(font
					(size 1 1)
					(thickness 0.15)
				)
				(justify mirror)
			)
		)
		(property "License" "Apache-2.0"
			(at 0 0 0)
			(layer "B.Fab")
			(hide yes)
			(effects
				(font
					(size 1 1)
					(thickness 0.15)
				)
				(justify mirror)
			)
		)
		(property "MPN" "CR0402-FX-33R0GLF"
			(at 0 0 0)
			(layer "B.Fab")
			(hide yes)
			(effects
				(font
					(size 1 1)
					(thickness 0.15)
				)
				(justify mirror)
			)
		)
		(property "Manufacturer" "Bourns"
			(at 0 0 0)
			(layer "B.Fab")
			(hide yes)
			(effects
				(font
					(size 1 1)
					(thickness 0.15)
				)
				(justify mirror)
			)
		)
		(property "Tolerance" "1%"
			(at 0 0 0)
			(layer "B.Fab")
			(hide yes)
			(effects
				(font
					(size 1 1)
					(thickness 0.15)
				)
				(justify mirror)
			)
		)
		(property "Val" "33R"
			(at 0 0 0)
			(layer "B.Fab")
			(hide yes)
			(effects
				(font
					(size 1 1)
					(thickness 0.15)
				)
				(justify mirror)
			)
		)
		(sheetname "FMC+ HSPC")
		(sheetfile "fmc-hspc.kicad_sch")
		(attr smd)
		(fp_rect
			(start -0.925 0.47)
			(end 0.925 -0.47)
			(stroke
				(width 0.05)
				(type default)
			)
			(fill no)
			(layer "B.CrtYd")
		)
		(fp_rect
			(start -0.5 0.25)
			(end 0.5 -0.25)
			(stroke
				(width 0.15)
				(type solid)
			)
			(fill no)
			(layer "B.Fab")
		)
		(pad "1" smd roundrect
			(at -0.48 0)
			(size 0.59 0.64)
			(layers "B.Cu" "B.Mask" "B.Paste")
			(roundrect_rratio 0.25)
			(net 595 "/FMC+ HSPC/GTR_REFCLK2_R_N")
			(pintype "passive")
		)
		(pad "2" smd roundrect
			(at 0.48 0)
			(size 0.59 0.64)
			(layers "B.Cu" "B.Mask" "B.Paste")
			(roundrect_rratio 0.25)
			(net 596 "/FMC+ HSPC/GTX116.REFCLK0_N")
			(pintype "passive")
		)
	)
)
